# BASEBOARD_FAB2 (Tioga Pass) — schematic netlist excerpt (pin names and nets, part order shuffled) for the footprints in the layout excerpt that follows; sources: Cadence DE-HDL packaged netlist, KiCad conversion of Wiwynn_Tioga_Pass_MB.brd

U1L1  TTL3126  74CBTLV3126 IC  pkg QFNLF  page 112
  OE(3)  = PWRGD_PVCCIN_CPU0
  A(3)  = XDP_TRST_N
  B(3)  = XDP_CPU_TRST_N
  OE(2)  = PWRGD_PVCCIN_CPU0
  A(2)  = XDP_TMS
  B(2)  = XDP_CPU_TMS
  B(1)  = XDP_CPU_TDO
  A(1)  = XDP_TDO
  OE(1)  = PWRGD_PVCCIN_CPU0
  B(0)  = XDP_CPU_TDI
  A(0)  = XDP_TDI
  OE(0)  = PWRGD_PVCCIN_CPU0

(kicad_pcb
	(version 20260206)
	(generator "pcbnew")
	(generator_version "10.0")
	(general
		(thickness 1.6)
		(legacy_teardrops no)
	)
	(paper "A4")
	(title_block
		(title "Wiwynn_Tioga_Pass_MB.brd")
		(comment 1 "Tioga Pass / footprints 3053-3053 of 4770")
	)
	(layers
		(0 "F.Cu" signal "TOP")
		(4 "In1.Cu" signal "L2GND")
		(6 "In2.Cu" signal "L3")
		(8 "In3.Cu" signal "L4GND")
		(10 "In4.Cu" signal "L5")
		(12 "In5.Cu" signal "L6GND")
		(14 "In6.Cu" signal "L7VCC")
		(16 "In7.Cu" signal "L8VCC")
		(18 "In8.Cu" signal "L9GND")
		(20 "In9.Cu" signal "L10")
		(22 "In10.Cu" signal "L11GND")
		(24 "In11.Cu" signal "L12")
		(26 "In12.Cu" signal "L13GND")
		(2 "B.Cu" signal "BOTTOM")
		(9 "F.Adhes" user "F.Adhesive")
		(11 "B.Adhes" user "B.Adhesive")
		(13 "F.Paste" user "Package Geometry/Pastemask Top")
		(15 "B.Paste" user "Package Geometry/Pastemask Bottom")
		(5 "F.SilkS" user "Ref Des/Silkscreen Top")
		(7 "B.SilkS" user "Ref Des/Silkscreen Bottom")
		(1 "F.Mask" user "Board Geometry/Soldermask Top")
		(3 "B.Mask" user "Board Geometry/Soldermask Bottom")
		(17 "Dwgs.User" user "User.Drawings")
		(19 "Cmts.User" user "User.Comments")
		(21 "Eco1.User" user "User.Eco1")
		(23 "Eco2.User" user "User.Eco2")
		(25 "Edge.Cuts" user "Board Geometry/Outline")
		(27 "Margin" user)
		(31 "F.CrtYd" user "Package Geometry/Place Bound Top")
		(29 "B.CrtYd" user "Package Geometry/Place Bound Bottom")
		(35 "F.Fab" user "Ref Des/Assembly Top")
		(33 "B.Fab" user "Ref Des/Assembly Bottom")
	)
	(footprint ""
		(layer "B.Cu")
		(at 459.880208 -150.876254)
		(property "Reference" "U1L1"
			(at 6.400292 -0.849376 0)
			(unlocked yes)
			(layer "B.SilkS")
			(effects
				(font
					(size 0.7874 0.5842)
					(thickness 0.1524)
				)
				(justify left mirror)
			)
		)
		(property "Value" ""
			(at 0 0 0)
			(layer "B.Fab")
			(effects
				(font
					(size 1.27 1.27)
				)
				(justify mirror)
			)
		)
		(duplicate_pad_numbers_are_jumpers no)
		(fp_circle
			(center 1.17856 -2.466086)
			(end 1.30556 -2.466086)
			(stroke
				(width 0.254)
				(type default)
			)
			(fill no)
			(layer "B.SilkS")
		)
		(fp_rect
			(start 0.9144 0.9144)
			(end -0.9144 -0.9144)
			(stroke
				(width 0)
				(type default)
			)
			(fill yes)
			(layer "B.Paste")
		)
		(fp_rect
			(start 1.82499 1.82499)
			(end -1.82499 -1.82499)
			(stroke
				(width 0)
				(type default)
			)
			(fill no)
			(layer "B.CrtYd")
		)
		(fp_line
			(start -1.82499 -1.82499)
			(end -1.82499 1.82499)
			(stroke
				(width 0.1)
				(type default)
			)
			(layer "B.Fab")
		)
		(fp_line
			(start -1.82499 1.82499)
			(end 1.82499 1.82499)
			(stroke
				(width 0.1)
				(type default)
			)
			(layer "B.Fab")
		)
		(fp_line
			(start 1.82499 -1.82499)
			(end -1.82499 -1.82499)
			(stroke
				(width 0.1)
				(type default)
			)
			(layer "B.Fab")
		)
		(fp_line
			(start 1.82499 1.82499)
			(end 1.82499 -1.82499)
			(stroke
				(width 0.1)
				(type default)
			)
			(layer "B.Fab")
		)
		(fp_circle
			(center 1.17856 -2.466086)
			(end 1.30556 -2.466086)
			(stroke
				(width 0.254)
				(type default)
			)
			(fill no)
			(layer "B.Fab")
		)
		(pad "1" smd custom
			(at 0.750062 -1.549908 180)
			(size 0.0762 0.0762)
			(layers "B.Cu" "B.Mask" "B.Paste")
			(net "PWRGD_PVCCIN_CPU0")
			(options
				(clearance outline)
				(anchor circle)
			)
			(primitives
				(gr_poly
					(pts
						(xy 0.1524 0.381)
						(arc
							(start 0.1524 -0.2286)
							(mid 0 -0.381)
							(end -0.1524 -0.2286)
						)
						(xy -0.1524 0.381)
					)
					(width 0)
					(fill yes)
				)
			)
		)
		(pad "2" smd custom
			(at 1.549908 -0.999998 180)
			(size 0.0762 0.0762)
			(layers "B.Cu" "B.Mask" "B.Paste")
			(net "XDP_TRST_N")
			(options
				(clearance outline)
				(anchor circle)
			)
			(primitives
				(gr_poly
					(pts
						(xy -0.381 0.1524)
						(arc
							(start 0.2286 0.1524)
							(mid 0.381 0)
							(end 0.2286 -0.1524)
						)
						(xy -0.381 -0.1524)
					)
					(width 0)
					(fill yes)
				)
			)
		)
		(pad "3" smd custom
			(at 1.549908 -0.500126 180)
			(size 0.0762 0.0762)
			(layers "B.Cu" "B.Mask" "B.Paste")
			(net "XDP_CPU_TRST_N")
			(options
				(clearance outline)
				(anchor circle)
			)
			(primitives
				(gr_poly
					(pts
						(xy -0.381 0.1524)
						(arc
							(start 0.2286 0.1524)
							(mid 0.381 0)
							(end 0.2286 -0.1524)
						)
						(xy -0.381 -0.1524)
					)
					(width 0)
					(fill yes)
				)
			)
		)
		(pad "4" smd custom
			(at 1.549908 0 180)
			(size 0.0762 0.0762)
			(layers "B.Cu" "B.Mask" "B.Paste")
			(net "PWRGD_PVCCIN_CPU0")
			(options
				(clearance outline)
				(anchor circle)
			)
			(primitives
				(gr_poly
					(pts
						(xy -0.381 0.1524)
						(arc
							(start 0.2286 0.1524)
							(mid 0.381 0)
							(end 0.2286 -0.1524)
						)
						(xy -0.381 -0.1524)
					)
					(width 0)
					(fill yes)
				)
			)
		)
		(pad "5" smd custom
			(at 1.549908 0.500126 180)
			(size 0.0762 0.0762)
			(layers "B.Cu" "B.Mask" "B.Paste")
			(net "XDP_TMS")
			(options
				(clearance outline)
				(anchor circle)
			)
			(primitives
				(gr_poly
					(pts
						(xy -0.381 0.1524)
						(arc
							(start 0.2286 0.1524)
							(mid 0.381 0)
							(end 0.2286 -0.1524)
						)
						(xy -0.381 -0.1524)
					)
					(width 0)
					(fill yes)
				)
			)
		)
		(pad "6" smd custom
			(at 1.549908 0.999998 180)
			(size 0.0762 0.0762)
			(layers "B.Cu" "B.Mask" "B.Paste")
			(net "XDP_CPU_TMS")
			(options
				(clearance outline)
				(anchor circle)
			)
			(primitives
				(gr_poly
					(pts
						(xy -0.381 0.1524)
						(arc
							(start 0.2286 0.1524)
							(mid 0.381 0)
							(end 0.2286 -0.1524)
						)
						(xy -0.381 -0.1524)
					)
					(width 0)
					(fill yes)
				)
			)
		)
		(pad "7" smd custom
			(at 0.750062 1.549908 180)
			(size 0.0762 0.0762)
			(layers "B.Cu" "B.Mask" "B.Paste")
			(net "GND")
			(options
				(clearance outline)
				(anchor circle)
			)
			(primitives
				(gr_poly
					(pts
						(xy -0.1524 -0.381)
						(arc
							(start -0.1524 0.2286)
							(mid 0 0.381)
							(end 0.1524 0.2286)
						)
						(xy 0.1524 -0.381)
					)
					(width 0)
					(fill yes)
				)
			)
		)
		(pad "8" smd custom
			(at -0.769874 1.549908 180)
			(size 0.0762 0.0762)
			(layers "B.Cu" "B.Mask" "B.Paste")
			(net "XDP_CPU_TDO")
			(options
				(clearance outline)
				(anchor circle)
			)
			(primitives
				(gr_poly
					(pts
						(xy -0.1524 -0.381)
						(arc
							(start -0.1524 0.2286)
							(mid 0 0.381)
							(end 0.1524 0.2286)
						)
						(xy 0.1524 -0.381)
					)
					(width 0)
					(fill yes)
				)
			)
		)
		(pad "9" smd custom
			(at -1.549908 0.999998 180)
			(size 0.0762 0.0762)
			(layers "B.Cu" "B.Mask" "B.Paste")
			(net "XDP_TDO")
			(options
				(clearance outline)
				(anchor circle)
			)
			(primitives
				(gr_poly
					(pts
						(xy 0.381 -0.1524)
						(arc
							(start -0.2286 -0.1524)
							(mid -0.381 0)
							(end -0.2286 0.1524)
						)
						(xy 0.381 0.1524)
					)
					(width 0)
					(fill yes)
				)
			)
		)
		(pad "10" smd custom
			(at -1.549908 0.500126 180)
			(size 0.0762 0.0762)
			(layers "B.Cu" "B.Mask" "B.Paste")
			(net "PWRGD_PVCCIN_CPU0")
			(options
				(clearance outline)
				(anchor circle)
			)
			(primitives
				(gr_poly
					(pts
						(xy 0.381 -0.1524)
						(arc
							(start -0.2286 -0.1524)
							(mid -0.381 0)
							(end -0.2286 0.1524)
						)
						(xy 0.381 0.1524)
					)
					(width 0)
					(fill yes)
				)
			)
		)
		(pad "11" smd custom
			(at -1.549908 0 180)
			(size 0.0762 0.0762)
			(layers "B.Cu" "B.Mask" "B.Paste")
			(net "XDP_CPU_TDI")
			(options
				(clearance outline)
				(anchor circle)
			)
			(primitives
				(gr_poly
					(pts
						(xy 0.381 -0.1524)
						(arc
							(start -0.2286 -0.1524)
							(mid -0.381 0)
							(end -0.2286 0.1524)
						)
						(xy 0.381 0.1524)
					)
					(width 0)
					(fill yes)
				)
			)
		)
		(pad "12" smd custom
			(at -1.549908 -0.500126 180)
			(size 0.0762 0.0762)
			(layers "B.Cu" "B.Mask" "B.Paste")
			(net "XDP_TDI")
			(options
				(clearance outline)
				(anchor circle)
			)
			(primitives
				(gr_poly
					(pts
						(xy 0.381 -0.1524)
						(arc
							(start -0.2286 -0.1524)
							(mid -0.381 0)
							(end -0.2286 0.1524)
						)
						(xy 0.381 0.1524)
					)
					(width 0)
					(fill yes)
				)
			)
		)
		(pad "13" smd custom
			(at -1.549908 -0.999998 180)
			(size 0.0762 0.0762)
			(layers "B.Cu" "B.Mask" "B.Paste")
			(net "PWRGD_PVCCIN_CPU0")
			(options
				(clearance outline)
				(anchor circle)
			)
			(primitives
				(gr_poly
					(pts
						(xy 0.381 -0.1524)
						(arc
							(start -0.2286 -0.1524)
							(mid -0.381 0)
							(end -0.2286 0.1524)
						)
						(xy 0.381 0.1524)
					)
					(width 0)
					(fill yes)
				)
			)
		)
		(pad "14" smd custom
			(at -0.750062 -1.549908 180)
			(size 0.0762 0.0762)
			(layers "B.Cu" "B.Mask" "B.Paste")
			(net "P3V3_STBY")
			(options
				(clearance outline)
				(anchor circle)
			)
			(primitives
				(gr_poly
					(pts
						(xy 0.1524 0.381)
						(arc
							(start 0.1524 -0.2286)
							(mid 0 -0.381)
							(end -0.1524 -0.2286)
						)
						(xy -0.1524 0.381)
					)
					(width 0)
					(fill yes)
				)
			)
		)
		(pad "15" smd rect
			(at 0 0 180)
			(size 1.8288 1.8288)
			(layers "B.Cu" "B.Mask" "B.Paste")
			(net "GND")
		)
	)
)
